# S9S_MB_2U (Grand Teton) — schematic netlist excerpt (pin names and nets, part order shuffled) for the footprints in the layout excerpt that follows; sources: Cadence DE-HDL packaged netlist, KiCad conversion of 03242023_DA0F0TMBIJ0_F0T_Motherboard_J_brd_V01_OCP.brd

R1202  Q_RES  20K 1% CHIP  pkg 0402LF  page 185 : A = P3V3_RTC_AUX ; B = RST_SRTCRST_N

U305  GTL2014PW  IC  pkg TSSOP14  page 225
  DIR  = PD_GTL2014_BMC_JTAG_DIR_1
  B0  = RST_CPU1_DRAM_GH_PLD_N
  B1  = RST_CPU1_DRAM_EF_PLD_N
  VREF  = P0V62_CPU1_RST_DDR_VREF
  B2  = RST_CPU1_DRAM_CD_PLD_N
  B3  = RST_CPU1_DRAM_AB_PLD_N
  GND_0  = GND
  GND_1  = GND
  A3  = RST_CPU1_DRAM_AB_PLD_LVT3_R_N
  A2  = RST_CPU1_DRAM_CD_PLD_LVT3_R_N
  GND_2  = GND
  A1  = RST_CPU1_DRAM_EF_PLD_LVT3_R_N
  A0  = RST_CPU1_DRAM_GH_PLD_LVT3_R_N
  VCC  = P3V3_AUX

(kicad_pcb
	(version 20260206)
	(generator "pcbnew")
	(generator_version "10.0")
	(general
		(thickness 1.6)
		(legacy_teardrops no)
	)
	(paper "A4")
	(title_block
		(title "03242023_DA0F0TMBIJ0_F0T_Motherboard_J_brd_V01_OCP.brd")
		(comment 1 "Grand Teton / footprints 2679-2680 of 6105")
	)
	(layers
		(0 "F.Cu" signal "TOP")
		(4 "In1.Cu" signal "GND")
		(6 "In2.Cu" signal "IN1")
		(8 "In3.Cu" signal "GND1")
		(10 "In4.Cu" signal "IN2")
		(12 "In5.Cu" signal "GND2")
		(14 "In6.Cu" signal "IN3")
		(16 "In7.Cu" signal "GND3")
		(18 "In8.Cu" signal "VCC")
		(20 "In9.Cu" signal "VCC1")
		(22 "In10.Cu" signal "GND4")
		(24 "In11.Cu" signal "IN4")
		(26 "In12.Cu" signal "GND5")
		(28 "In13.Cu" signal "IN5")
		(30 "In14.Cu" signal "GND6")
		(32 "In15.Cu" signal "IN6")
		(34 "In16.Cu" signal "GND7")
		(2 "B.Cu" signal "BOTTOM")
		(9 "F.Adhes" user "F.Adhesive")
		(11 "B.Adhes" user "B.Adhesive")
		(13 "F.Paste" user "Package Geometry/Pastemask Top")
		(15 "B.Paste" user "Package Geometry/Pastemask Bottom")
		(5 "F.SilkS" user "Ref Des/Silkscreen Top")
		(7 "B.SilkS" user "Ref Des/Silkscreen Bottom")
		(1 "F.Mask" user "Board Geometry/Soldermask Top")
		(3 "B.Mask" user "Board Geometry/Soldermask Bottom")
		(17 "Dwgs.User" user "User.Drawings")
		(19 "Cmts.User" user "User.Comments")
		(21 "Eco1.User" user "User.Eco1")
		(23 "Eco2.User" user "User.Eco2")
		(25 "Edge.Cuts" user "Board Geometry/Outline")
		(27 "Margin" user)
		(31 "F.CrtYd" user "Package Geometry/Place Bound Top")
		(29 "B.CrtYd" user "Package Geometry/Place Bound Bottom")
		(35 "F.Fab" user "Ref Des/Assembly Top")
		(33 "B.Fab" user "Ref Des/Assembly Bottom")
	)
	(footprint ""
		(layer "F.Cu")
		(at 325.193914 -25.102312)
		(property "Reference" "R1202"
			(at 0 0 0)
			(layer "F.SilkS")
			(hide yes)
			(effects
				(font
					(size 1.27 1.27)
				)
			)
		)
		(property "Value" ""
			(at 0 0 0)
			(layer "F.Fab")
			(effects
				(font
					(size 1.27 1.27)
				)
			)
		)
		(duplicate_pad_numbers_are_jumpers no)
		(fp_line
			(start -0.7874 -0.4064)
			(end 0.7874 -0.4064)
			(stroke
				(width 0.1524)
				(type default)
			)
			(layer "F.SilkS")
		)
		(fp_line
			(start -0.7874 0.4064)
			(end -0.7874 -0.4064)
			(stroke
				(width 0.1524)
				(type default)
			)
			(layer "F.SilkS")
		)
		(fp_line
			(start 0.7874 -0.4064)
			(end 0.7874 0.4064)
			(stroke
				(width 0.1524)
				(type default)
			)
			(layer "F.SilkS")
		)
		(fp_line
			(start 0.7874 0.4064)
			(end -0.7874 0.4064)
			(stroke
				(width 0.1524)
				(type default)
			)
			(layer "F.SilkS")
		)
		(fp_line
			(start -0.67945 -0.305054)
			(end -0.12065 -0.305054)
			(stroke
				(width 0.1)
				(type default)
			)
			(layer "F.Fab")
		)
		(fp_line
			(start -0.67945 0.3048)
			(end -0.67945 -0.305054)
			(stroke
				(width 0.1)
				(type default)
			)
			(layer "F.Fab")
		)
		(fp_line
			(start -0.12065 -0.305054)
			(end -0.12065 -0.2794)
			(stroke
				(width 0.1)
				(type default)
			)
			(layer "F.Fab")
		)
		(fp_line
			(start -0.12065 -0.2794)
			(end 0.12065 -0.2794)
			(stroke
				(width 0.1)
				(type default)
			)
			(layer "F.Fab")
		)
		(fp_line
			(start -0.12065 0.2794)
			(end -0.12065 0.3048)
			(stroke
				(width 0.1)
				(type default)
			)
			(layer "F.Fab")
		)
		(fp_line
			(start -0.12065 0.3048)
			(end -0.67945 0.3048)
			(stroke
				(width 0.1)
				(type default)
			)
			(layer "F.Fab")
		)
		(fp_line
			(start 0.120396 0.2794)
			(end -0.12065 0.2794)
			(stroke
				(width 0.1)
				(type default)
			)
			(layer "F.Fab")
		)
		(fp_line
			(start 0.120396 0.3048)
			(end 0.120396 0.2794)
			(stroke
				(width 0.1)
				(type default)
			)
			(layer "F.Fab")
		)
		(fp_line
			(start 0.12065 -0.3048)
			(end 0.67945 -0.3048)
			(stroke
				(width 0.1)
				(type default)
			)
			(layer "F.Fab")
		)
		(fp_line
			(start 0.12065 -0.2794)
			(end 0.12065 -0.3048)
			(stroke
				(width 0.1)
				(type default)
			)
			(layer "F.Fab")
		)
		(fp_line
			(start 0.67945 -0.3048)
			(end 0.67945 0.3048)
			(stroke
				(width 0.1)
				(type default)
			)
			(layer "F.Fab")
		)
		(fp_line
			(start 0.67945 0.3048)
			(end 0.120396 0.3048)
			(stroke
				(width 0.1)
				(type default)
			)
			(layer "F.Fab")
		)
		(pad "1" smd circle
			(at -0.40005 0)
			(size 0 0)
			(layers "F.Cu" "F.Mask" "F.Paste")
			(net "P3V3_RTC_AUX")
		)
		(pad "2" smd circle
			(at 0.40005 0)
			(size 0 0)
			(layers "F.Cu" "F.Mask" "F.Paste")
			(net "RST_SRTCRST_N")
		)
	)
	(footprint ""
		(layer "F.Cu")
		(at 123.96978 -113.121948 -90)
		(property "Reference" "U305"
			(at -2.09169 -3.21818 0)
			(unlocked yes)
			(layer "F.SilkS")
			(effects
				(font
					(size 0.7874 0.5842)
					(thickness 0.1524)
				)
				(justify left)
			)
		)
		(property "Value" ""
			(at 0 0 270)
			(layer "F.Fab")
			(effects
				(font
					(size 1.27 1.27)
				)
			)
		)
		(duplicate_pad_numbers_are_jumpers no)
		(fp_line
			(start -2.0066 2.5527)
			(end -2.0066 -2.5527)
			(stroke
				(width 0.1524)
				(type default)
			)
			(layer "F.SilkS")
		)
		(fp_line
			(start 2.0066 2.5527)
			(end -2.0066 2.5527)
			(stroke
				(width 0.1524)
				(type default)
			)
			(layer "F.SilkS")
		)
		(fp_line
			(start 0 -1.9812)
			(end 0.5715 -2.5527)
			(stroke
				(width 0.1524)
				(type default)
			)
			(layer "F.SilkS")
		)
		(fp_line
			(start -2.0066 -2.5527)
			(end -0.5715 -2.5527)
			(stroke
				(width 0.1524)
				(type default)
			)
			(layer "F.SilkS")
		)
		(fp_line
			(start -0.5715 -2.5527)
			(end 0 -1.9812)
			(stroke
				(width 0.1524)
				(type default)
			)
			(layer "F.SilkS")
		)
		(fp_line
			(start 0.5715 -2.5527)
			(end 2.0066 -2.5527)
			(stroke
				(width 0.1524)
				(type default)
			)
			(layer "F.SilkS")
		)
		(fp_line
			(start 2.0066 -2.5527)
			(end 2.0066 2.5527)
			(stroke
				(width 0.1524)
				(type default)
			)
			(layer "F.SilkS")
		)
		(fp_poly
			(pts
				(xy -4.36372 -2.233168) (xy -3.81 -1.905) (xy -4.36372 -1.608328)
			)
			(stroke
				(width 0)
				(type default)
			)
			(fill yes)
			(layer "F.SilkS")
		)
		(fp_line
			(start -2.249932 2.549906)
			(end -2.249932 -2.549906)
			(stroke
				(width 0.1)
				(type default)
			)
			(layer "F.Fab")
		)
		(fp_line
			(start 2.249932 2.549906)
			(end -2.249932 2.549906)
			(stroke
				(width 0.1)
				(type default)
			)
			(layer "F.Fab")
		)
		(fp_line
			(start -2.249932 -2.549906)
			(end 2.249932 -2.549906)
			(stroke
				(width 0.1)
				(type default)
			)
			(layer "F.Fab")
		)
		(fp_line
			(start 2.249932 -2.549906)
			(end 2.249932 2.549906)
			(stroke
				(width 0.1)
				(type default)
			)
			(layer "F.Fab")
		)
		(fp_poly
			(pts
				(xy -4.36372 -1.608328) (xy -4.36372 -2.233168) (xy -3.81 -1.905)
			)
			(stroke
				(width 0)
				(type default)
			)
			(fill yes)
			(layer "F.Fab")
		)
		(pad "1" smd rect
			(at -2.921 -1.949958 180)
			(size 0.3556 1.4986)
			(layers "F.Cu" "F.Mask" "F.Paste")
			(net "PD_GTL2014_BMC_JTAG_DIR_1")
		)
		(pad "2" smd rect
			(at -2.921 -1.299972 180)
			(size 0.3556 1.4986)
			(layers "F.Cu" "F.Mask" "F.Paste")
			(net "RST_CPU1_DRAM_GH_PLD_N")
		)
		(pad "3" smd rect
			(at -2.921 -0.649986 180)
			(size 0.3556 1.4986)
			(layers "F.Cu" "F.Mask" "F.Paste")
			(net "RST_CPU1_DRAM_EF_PLD_N")
		)
		(pad "4" smd rect
			(at -2.921 0 180)
			(size 0.3556 1.4986)
			(layers "F.Cu" "F.Mask" "F.Paste")
			(net "P0V62_CPU1_RST_DDR_VREF")
		)
		(pad "5" smd rect
			(at -2.921 0.649986 180)
			(size 0.3556 1.4986)
			(layers "F.Cu" "F.Mask" "F.Paste")
			(net "RST_CPU1_DRAM_CD_PLD_N")
		)
		(pad "6" smd rect
			(at -2.921 1.299972 180)
			(size 0.3556 1.4986)
			(layers "F.Cu" "F.Mask" "F.Paste")
			(net "RST_CPU1_DRAM_AB_PLD_N")
		)
		(pad "7" smd rect
			(at -2.921 1.949958 180)
			(size 0.3556 1.4986)
			(layers "F.Cu" "F.Mask" "F.Paste")
			(net "GND")
		)
		(pad "8" smd rect
			(at 2.921 1.949958 180)
			(size 0.3556 1.4986)
			(layers "F.Cu" "F.Mask" "F.Paste")
			(net "GND")
		)
		(pad "9" smd rect
			(at 2.921 1.299972 180)
			(size 0.3556 1.4986)
			(layers "F.Cu" "F.Mask" "F.Paste")
			(net "RST_CPU1_DRAM_AB_PLD_LVT3_R_N")
		)
		(pad "10" smd rect
			(at 2.921 0.649986 180)
			(size 0.3556 1.4986)
			(layers "F.Cu" "F.Mask" "F.Paste")
			(net "RST_CPU1_DRAM_CD_PLD_LVT3_R_N")
		)
		(pad "11" smd rect
			(at 2.921 0 180)
			(size 0.3556 1.4986)
			(layers "F.Cu" "F.Mask" "F.Paste")
			(net "GND")
		)
		(pad "12" smd rect
			(at 2.921 -0.649986 180)
			(size 0.3556 1.4986)
			(layers "F.Cu" "F.Mask" "F.Paste")
			(net "RST_CPU1_DRAM_EF_PLD_LVT3_R_N")
		)
		(pad "13" smd rect
			(at 2.921 -1.299972 180)
			(size 0.3556 1.4986)
			(layers "F.Cu" "F.Mask" "F.Paste")
			(net "RST_CPU1_DRAM_GH_PLD_LVT3_R_N")
		)
		(pad "14" smd rect
			(at 2.921 -1.949958 180)
			(size 0.3556 1.4986)
			(layers "F.Cu" "F.Mask" "F.Paste")
			(net "P3V3_AUX")
		)
	)
)
